(kicad_pcb
	(version 20260206)
	(generator "pcbnew")
	(generator_version "10.0")
	(general
		(thickness 1.6)
		(legacy_teardrops no)
	)
	(paper "A4")
	(title_block
		(title "04192023_DAF0TMB3IC0_F0TG_MB_C_brd_V02_OCP.brd")
		(comment 1 "Grand Teton / footprints 1210-1216 of 8354")
	)
	(layers
		(0 "F.Cu" signal "TOP")
		(4 "In1.Cu" signal "GND")
		(6 "In2.Cu" signal "IN1")
		(8 "In3.Cu" signal "GND1")
		(10 "In4.Cu" signal "IN2")
		(12 "In5.Cu" signal "GND2")
		(14 "In6.Cu" signal "IN3")
		(16 "In7.Cu" signal "GND3")
		(18 "In8.Cu" signal "VCC")
		(20 "In9.Cu" signal "VCC1")
		(22 "In10.Cu" signal "GND4")
		(24 "In11.Cu" signal "IN4")
		(26 "In12.Cu" signal "GND5")
		(28 "In13.Cu" signal "IN5")
		(30 "In14.Cu" signal "GND6")
		(32 "In15.Cu" signal "IN6")
		(34 "In16.Cu" signal "GND7")
		(2 "B.Cu" signal "BOTTOM")
		(9 "F.Adhes" user "F.Adhesive")
		(11 "B.Adhes" user "B.Adhesive")
		(13 "F.Paste" user "Package Geometry/Pastemask Top")
		(15 "B.Paste" user "Package Geometry/Pastemask Bottom")
		(5 "F.SilkS" user "Ref Des/Silkscreen Top")
		(7 "B.SilkS" user "Ref Des/Silkscreen Bottom")
		(1 "F.Mask" user "Board Geometry/Soldermask Top")
		(3 "B.Mask" user "Board Geometry/Soldermask Bottom")
		(17 "Dwgs.User" user "User.Drawings")
		(19 "Cmts.User" user "User.Comments")
		(21 "Eco1.User" user "User.Eco1")
		(23 "Eco2.User" user "User.Eco2")
		(25 "Edge.Cuts" user "Board Geometry/Outline")
		(27 "Margin" user)
		(31 "F.CrtYd" user "Package Geometry/Place Bound Top")
		(29 "B.CrtYd" user "Package Geometry/Place Bound Bottom")
		(35 "F.Fab" user "Ref Des/Assembly Top")
		(33 "B.Fab" user "Ref Des/Assembly Bottom")
	)
	(footprint ""
		(layer "F.Cu")
		(at 68.16852 -394.3604 -90)
		(property "Reference" "R6720"
			(at 0 0 270)
			(layer "F.SilkS")
			(hide yes)
			(effects
				(font
					(size 1.27 1.27)
				)
			)
		)
		(property "Value" ""
			(at 0 0 270)
			(layer "F.Fab")
			(effects
				(font
					(size 1.27 1.27)
				)
			)
		)
		(duplicate_pad_numbers_are_jumpers no)
		(fp_line
			(start -0.32512 0.175006)
			(end -0.32512 -0.175006)
			(stroke
				(width 0.1)
				(type default)
			)
			(layer "F.Fab")
		)
		(fp_line
			(start 0.32512 0.175006)
			(end -0.32512 0.175006)
			(stroke
				(width 0.1)
				(type default)
			)
			(layer "F.Fab")
		)
		(fp_line
			(start -0.32512 -0.175006)
			(end 0.32512 -0.175006)
			(stroke
				(width 0.1)
				(type default)
			)
			(layer "F.Fab")
		)
		(fp_line
			(start 0.32512 -0.175006)
			(end 0.32512 0.175006)
			(stroke
				(width 0.1)
				(type default)
			)
			(layer "F.Fab")
		)
		(pad "1" smd rect
			(at -0.2667 0 270)
			(size 0.3048 0.381)
			(layers "F.Cu" "F.Mask" "F.Paste")
			(net "RST_RT_CPU1_P0_PERST_R_N")
		)
		(pad "2" smd rect
			(at 0.2667 0 90)
			(size 0.3048 0.381)
			(layers "F.Cu" "F.Mask" "F.Paste")
			(net "GND")
		)
	)
	(footprint ""
		(layer "F.Cu")
		(at 112.438942 -21.7678 -90)
		(property "Reference" "R6262"
			(at 0 0 270)
			(layer "F.SilkS")
			(hide yes)
			(effects
				(font
					(size 1.27 1.27)
				)
			)
		)
		(property "Value" ""
			(at 0 0 270)
			(layer "F.Fab")
			(effects
				(font
					(size 1.27 1.27)
				)
			)
		)
		(duplicate_pad_numbers_are_jumpers no)
		(fp_line
			(start -0.7874 0.4064)
			(end -0.7874 -0.4064)
			(stroke
				(width 0.1524)
				(type default)
			)
			(layer "F.SilkS")
		)
		(fp_line
			(start 0.7874 0.4064)
			(end -0.7874 0.4064)
			(stroke
				(width 0.1524)
				(type default)
			)
			(layer "F.SilkS")
		)
		(fp_line
			(start -0.7874 -0.4064)
			(end 0.7874 -0.4064)
			(stroke
				(width 0.1524)
				(type default)
			)
			(layer "F.SilkS")
		)
		(fp_line
			(start 0.7874 -0.4064)
			(end 0.7874 0.4064)
			(stroke
				(width 0.1524)
				(type default)
			)
			(layer "F.SilkS")
		)
		(fp_line
			(start -0.67945 0.3048)
			(end -0.67945 -0.305054)
			(stroke
				(width 0.1)
				(type default)
			)
			(layer "F.Fab")
		)
		(fp_line
			(start -0.12065 0.3048)
			(end -0.67945 0.3048)
			(stroke
				(width 0.1)
				(type default)
			)
			(layer "F.Fab")
		)
		(fp_line
			(start 0.120396 0.3048)
			(end 0.120396 0.2794)
			(stroke
				(width 0.1)
				(type default)
			)
			(layer "F.Fab")
		)
		(fp_line
			(start 0.67945 0.3048)
			(end 0.120396 0.3048)
			(stroke
				(width 0.1)
				(type default)
			)
			(layer "F.Fab")
		)
		(fp_line
			(start -0.12065 0.2794)
			(end -0.12065 0.3048)
			(stroke
				(width 0.1)
				(type default)
			)
			(layer "F.Fab")
		)
		(fp_line
			(start 0.120396 0.2794)
			(end -0.12065 0.2794)
			(stroke
				(width 0.1)
				(type default)
			)
			(layer "F.Fab")
		)
		(fp_line
			(start -0.12065 -0.2794)
			(end 0.12065 -0.2794)
			(stroke
				(width 0.1)
				(type default)
			)
			(layer "F.Fab")
		)
		(fp_line
			(start 0.12065 -0.2794)
			(end 0.12065 -0.3048)
			(stroke
				(width 0.1)
				(type default)
			)
			(layer "F.Fab")
		)
		(fp_line
			(start 0.12065 -0.3048)
			(end 0.67945 -0.3048)
			(stroke
				(width 0.1)
				(type default)
			)
			(layer "F.Fab")
		)
		(fp_line
			(start 0.67945 -0.3048)
			(end 0.67945 0.3048)
			(stroke
				(width 0.1)
				(type default)
			)
			(layer "F.Fab")
		)
		(fp_line
			(start -0.67945 -0.305054)
			(end -0.12065 -0.305054)
			(stroke
				(width 0.1)
				(type default)
			)
			(layer "F.Fab")
		)
		(fp_line
			(start -0.12065 -0.305054)
			(end -0.12065 -0.2794)
			(stroke
				(width 0.1)
				(type default)
			)
			(layer "F.Fab")
		)
		(pad "1" smd circle
			(at -0.40005 0 270)
			(size 0 0)
			(layers "F.Cu" "F.Mask" "F.Paste")
			(net "USB_HUB2_TI_VDD_MRP_USB3DN_RXDM1")
		)
		(pad "2" smd circle
			(at 0.40005 0 270)
			(size 0 0)
			(layers "F.Cu" "F.Mask" "F.Paste")
			(net "P1V2_CPU0_USB2_DVDD12")
		)
	)
	(footprint ""
		(layer "F.Cu")
		(at 509.384808 -142.846806 90)
		(property "Reference" "X8008"
			(at -2.000758 1.744472 0)
			(unlocked yes)
			(layer "F.SilkS")
			(effects
				(font
					(size 0.7874 0.5842)
					(thickness 0.1524)
				)
				(justify left)
			)
		)
		(property "Value" ""
			(at 0 0 90)
			(layer "F.Fab")
			(effects
				(font
					(size 1.27 1.27)
				)
			)
		)
		(property "Device Type" "TP_TDR_4P_FTS_TH-TP_TDR_4P_DIP,EMPTY,TP15"
			(at 1.30175 1.27 180)
			(unlocked yes)
			(layer "F.Fab")
			(hide yes)
			(effects
				(font
					(size 0.635 0.4064)
					(thickness 0.1524)
				)
			)
		)
		(property "User Part Number" "N_A"
			(at 1.30175 1.27 180)
			(unlocked yes)
			(layer "Cmts.User")
			(hide yes)
			(effects
				(font
					(size 0.635 0.4064)
					(thickness 0.1524)
				)
			)
		)
		(duplicate_pad_numbers_are_jumpers no)
		(fp_line
			(start 2.54 -1.27)
			(end 0 -1.27)
			(stroke
				(width 0.1524)
				(type default)
			)
			(layer "F.SilkS")
		)
		(fp_line
			(start 0 -1.27)
			(end 0 -0.635)
			(stroke
				(width 0.1524)
				(type default)
			)
			(layer "F.SilkS")
		)
		(fp_line
			(start 2.54 -1.1303)
			(end 2.54 -1.27)
			(stroke
				(width 0.1524)
				(type default)
			)
			(layer "F.SilkS")
		)
		(fp_line
			(start 0 0.635)
			(end 0 1.905)
			(stroke
				(width 0.1524)
				(type default)
			)
			(layer "F.SilkS")
		)
		(fp_line
			(start 2.54 1.4097)
			(end 2.54 1.1303)
			(stroke
				(width 0.1524)
				(type default)
			)
			(layer "F.SilkS")
		)
		(fp_line
			(start 0 3.175)
			(end 0 3.81)
			(stroke
				(width 0.1524)
				(type default)
			)
			(layer "F.SilkS")
		)
		(fp_line
			(start 2.54 3.81)
			(end 2.54 3.6703)
			(stroke
				(width 0.1524)
				(type default)
			)
			(layer "F.SilkS")
		)
		(fp_line
			(start 0 3.81)
			(end 2.54 3.81)
			(stroke
				(width 0.1524)
				(type default)
			)
			(layer "F.SilkS")
		)
		(fp_poly
			(pts
				(xy -2.285746 -0.762) (xy -0.761746 0) (xy -2.285746 0.762)
			)
			(stroke
				(width 0)
				(type default)
			)
			(fill yes)
			(layer "F.SilkS")
		)
		(fp_line
			(start 2.54 -1.27)
			(end 0 -1.27)
			(stroke
				(width 0.1)
				(type default)
			)
			(layer "F.Fab")
		)
		(fp_line
			(start 0 -1.27)
			(end 0 3.81)
			(stroke
				(width 0.1)
				(type default)
			)
			(layer "F.Fab")
		)
		(fp_line
			(start 2.54 3.81)
			(end 2.54 -1.27)
			(stroke
				(width 0.1)
				(type default)
			)
			(layer "F.Fab")
		)
		(fp_line
			(start 0 3.81)
			(end 2.54 3.81)
			(stroke
				(width 0.1)
				(type default)
			)
			(layer "F.Fab")
		)
		(fp_poly
			(pts
				(xy -0.761746 0) (xy -2.285746 -0.762) (xy -2.285746 0.762)
			)
			(stroke
				(width 0)
				(type default)
			)
			(fill yes)
			(layer "F.Fab")
		)
		(pad "1" thru_hole circle
			(at 0 0 90)
			(size 1.0033 1.0033)
			(drill 0.249936)
			(layers "*.Cu" "*.Mask")
			(remove_unused_layers no)
			(net "TDR_DIFF_85_IN1_DN")
			(clearance 0.10795)
			(thermal_gap 0.10795)
			(padstack
				(mode front_inner_back)
				(layer "Inner"
					(shape circle)
					(size 0.8001 0.8001)
					(clearance 0.1524)
				)
				(layer "B.Cu"
					(shape circle)
					(size 1.0033 1.0033)
					(clearance 0.10795)
				)
			)
		)
		(pad "2" thru_hole circle
			(at 2.54 0 90)
			(size 1.9939 1.9939)
			(drill 0.249936)
			(layers "*.Cu" "*.Mask")
			(remove_unused_layers no)
			(net "T1_GND")
			(clearance 0.10795)
			(thermal_gap 0.10795)
			(padstack
				(mode front_inner_back)
				(layer "Inner"
					(shape circle)
					(size 0.8001 0.8001)
					(clearance 0.1524)
				)
				(layer "B.Cu"
					(shape circle)
					(size 1.9939 1.9939)
					(clearance 0.10795)
				)
			)
		)
		(pad "3" thru_hole circle
			(at 2.54 2.54 90)
			(size 1.9939 1.9939)
			(drill 0.249936)
			(layers "*.Cu" "*.Mask")
			(remove_unused_layers no)
			(net "T1_GND")
			(clearance 0.10795)
			(thermal_gap 0.10795)
			(padstack
				(mode front_inner_back)
				(layer "Inner"
					(shape circle)
					(size 0.8001 0.8001)
					(clearance 0.1524)
				)
				(layer "B.Cu"
					(shape circle)
					(size 1.9939 1.9939)
					(clearance 0.10795)
				)
			)
		)
		(pad "4" thru_hole circle
			(at 0 2.54 90)
			(size 1.0033 1.0033)
			(drill 0.249936)
			(layers "*.Cu" "*.Mask")
			(remove_unused_layers no)
			(net "TDR_DIFF_85_IN1_DP")
			(clearance 0.10795)
			(thermal_gap 0.10795)
			(padstack
				(mode front_inner_back)
				(layer "Inner"
					(shape circle)
					(size 0.8001 0.8001)
					(clearance 0.1524)
				)
				(layer "B.Cu"
					(shape circle)
					(size 1.0033 1.0033)
					(clearance 0.10795)
				)
			)
		)
	)
	(footprint ""
		(layer "F.Cu")
		(at 365.62792 -395.333474)
		(property "Reference" "R616"
			(at 0 0 0)
			(layer "F.SilkS")
			(hide yes)
			(effects
				(font
					(size 1.27 1.27)
				)
			)
		)
		(property "Value" ""
			(at 0 0 0)
			(layer "F.Fab")
			(effects
				(font
					(size 1.27 1.27)
				)
			)
		)
		(duplicate_pad_numbers_are_jumpers no)
		(fp_line
			(start -0.32512 -0.175006)
			(end 0.32512 -0.175006)
			(stroke
				(width 0.1)
				(type default)
			)
			(layer "F.Fab")
		)
		(fp_line
			(start -0.32512 0.175006)
			(end -0.32512 -0.175006)
			(stroke
				(width 0.1)
				(type default)
			)
			(layer "F.Fab")
		)
		(fp_line
			(start 0.32512 -0.175006)
			(end 0.32512 0.175006)
			(stroke
				(width 0.1)
				(type default)
			)
			(layer "F.Fab")
		)
		(fp_line
			(start 0.32512 0.175006)
			(end -0.32512 0.175006)
			(stroke
				(width 0.1)
				(type default)
			)
			(layer "F.Fab")
		)
		(pad "1" smd rect
			(at -0.2667 0)
			(size 0.3048 0.381)
			(layers "F.Cu" "F.Mask" "F.Paste")
			(net "CLK_100M_RETIMER_CPU0_P3_R_DN")
		)
		(pad "2" smd rect
			(at 0.2667 0 180)
			(size 0.3048 0.381)
			(layers "F.Cu" "F.Mask" "F.Paste")
			(net "CLK_100M_RETIMER_CPU0_P3_DN")
		)
	)
	(footprint ""
		(layer "F.Cu")
		(at 289.17392 -399.553684 -90)
		(property "Reference" "R1044"
			(at 0 0 270)
			(layer "F.SilkS")
			(hide yes)
			(effects
				(font
					(size 1.27 1.27)
				)
			)
		)
		(property "Value" ""
			(at 0 0 270)
			(layer "F.Fab")
			(effects
				(font
					(size 1.27 1.27)
				)
			)
		)
		(duplicate_pad_numbers_are_jumpers no)
		(fp_line
			(start -0.32512 0.175006)
			(end -0.32512 -0.175006)
			(stroke
				(width 0.1)
				(type default)
			)
			(layer "F.Fab")
		)
		(fp_line
			(start 0.32512 0.175006)
			(end -0.32512 0.175006)
			(stroke
				(width 0.1)
				(type default)
			)
			(layer "F.Fab")
		)
		(fp_line
			(start -0.32512 -0.175006)
			(end 0.32512 -0.175006)
			(stroke
				(width 0.1)
				(type default)
			)
			(layer "F.Fab")
		)
		(fp_line
			(start 0.32512 -0.175006)
			(end 0.32512 0.175006)
			(stroke
				(width 0.1)
				(type default)
			)
			(layer "F.Fab")
		)
		(pad "1" smd rect
			(at -0.2667 0 270)
			(size 0.3048 0.381)
			(layers "F.Cu" "F.Mask" "F.Paste")
			(net "U15_E2")
		)
		(pad "2" smd rect
			(at 0.2667 0 90)
			(size 0.3048 0.381)
			(layers "F.Cu" "F.Mask" "F.Paste")
			(net "GND")
		)
	)
	(footprint ""
		(layer "F.Cu")
		(at 14.078458 -418.690298 90)
		(property "Reference" "R6177"
			(at 0 0 90)
			(layer "F.SilkS")
			(hide yes)
			(effects
				(font
					(size 1.27 1.27)
				)
			)
		)
		(property "Value" ""
			(at 0 0 90)
			(layer "F.Fab")
			(effects
				(font
					(size 1.27 1.27)
				)
			)
		)
		(duplicate_pad_numbers_are_jumpers no)
		(fp_line
			(start 0.7874 -0.4064)
			(end 0.7874 0.4064)
			(stroke
				(width 0.1524)
				(type default)
			)
			(layer "F.SilkS")
		)
		(fp_line
			(start -0.7874 -0.4064)
			(end 0.7874 -0.4064)
			(stroke
				(width 0.1524)
				(type default)
			)
			(layer "F.SilkS")
		)
		(fp_line
			(start 0.7874 0.4064)
			(end -0.7874 0.4064)
			(stroke
				(width 0.1524)
				(type default)
			)
			(layer "F.SilkS")
		)
		(fp_line
			(start -0.7874 0.4064)
			(end -0.7874 -0.4064)
			(stroke
				(width 0.1524)
				(type default)
			)
			(layer "F.SilkS")
		)
		(fp_line
			(start -0.12065 -0.305054)
			(end -0.12065 -0.2794)
			(stroke
				(width 0.1)
				(type default)
			)
			(layer "F.Fab")
		)
		(fp_line
			(start -0.67945 -0.305054)
			(end -0.12065 -0.305054)
			(stroke
				(width 0.1)
				(type default)
			)
			(layer "F.Fab")
		)
		(fp_line
			(start 0.67945 -0.3048)
			(end 0.67945 0.3048)
			(stroke
				(width 0.1)
				(type default)
			)
			(layer "F.Fab")
		)
		(fp_line
			(start 0.12065 -0.3048)
			(end 0.67945 -0.3048)
			(stroke
				(width 0.1)
				(type default)
			)
			(layer "F.Fab")
		)
		(fp_line
			(start 0.12065 -0.2794)
			(end 0.12065 -0.3048)
			(stroke
				(width 0.1)
				(type default)
			)
			(layer "F.Fab")
		)
		(fp_line
			(start -0.12065 -0.2794)
			(end 0.12065 -0.2794)
			(stroke
				(width 0.1)
				(type default)
			)
			(layer "F.Fab")
		)
		(fp_line
			(start 0.120396 0.2794)
			(end -0.12065 0.2794)
			(stroke
				(width 0.1)
				(type default)
			)
			(layer "F.Fab")
		)
		(fp_line
			(start -0.12065 0.2794)
			(end -0.12065 0.3048)
			(stroke
				(width 0.1)
				(type default)
			)
			(layer "F.Fab")
		)
		(fp_line
			(start 0.67945 0.3048)
			(end 0.120396 0.3048)
			(stroke
				(width 0.1)
				(type default)
			)
			(layer "F.Fab")
		)
		(fp_line
			(start 0.120396 0.3048)
			(end 0.120396 0.2794)
			(stroke
				(width 0.1)
				(type default)
			)
			(layer "F.Fab")
		)
		(fp_line
			(start -0.12065 0.3048)
			(end -0.67945 0.3048)
			(stroke
				(width 0.1)
				(type default)
			)
			(layer "F.Fab")
		)
		(fp_line
			(start -0.67945 0.3048)
			(end -0.67945 -0.305054)
			(stroke
				(width 0.1)
				(type default)
			)
			(layer "F.Fab")
		)
		(pad "1" smd circle
			(at -0.40005 0 90)
			(size 0 0)
			(layers "F.Cu" "F.Mask" "F.Paste")
			(net "P3V3_AUX")
		)
		(pad "2" smd circle
			(at 0.40005 0 90)
			(size 0 0)
			(layers "F.Cu" "F.Mask" "F.Paste")
			(net "FM_P2E_BUF2_SD_TH")
		)
	)
	(footprint ""
		(layer "F.Cu")
		(at 83.222084 -39.65448 180)
		(property "Reference" "R6057"
			(at 0 0 180)
			(layer "F.SilkS")
			(hide yes)
			(effects
				(font
					(size 1.27 1.27)
				)
			)
		)
		(property "Value" ""
			(at 0 0 180)
			(layer "F.Fab")
			(effects
				(font
					(size 1.27 1.27)
				)
			)
		)
		(duplicate_pad_numbers_are_jumpers no)
		(fp_line
			(start 0.7874 0.4064)
			(end -0.7874 0.4064)
			(stroke
				(width 0.1524)
				(type default)
			)
			(layer "F.SilkS")
		)
		(fp_line
			(start 0.7874 -0.4064)
			(end 0.7874 0.4064)
			(stroke
				(width 0.1524)
				(type default)
			)
			(layer "F.SilkS")
		)
		(fp_line
			(start -0.7874 0.4064)
			(end -0.7874 -0.4064)
			(stroke
				(width 0.1524)
				(type default)
			)
			(layer "F.SilkS")
		)
		(fp_line
			(start -0.7874 -0.4064)
			(end 0.7874 -0.4064)
			(stroke
				(width 0.1524)
				(type default)
			)
			(layer "F.SilkS")
		)
		(fp_line
			(start 0.67945 0.3048)
			(end 0.120396 0.3048)
			(stroke
				(width 0.1)
				(type default)
			)
			(layer "F.Fab")
		)
		(fp_line
			(start 0.67945 -0.3048)
			(end 0.67945 0.3048)
			(stroke
				(width 0.1)
				(type default)
			)
			(layer "F.Fab")
		)
		(fp_line
			(start 0.12065 -0.2794)
			(end 0.12065 -0.3048)
			(stroke
				(width 0.1)
				(type default)
			)
			(layer "F.Fab")
		)
		(fp_line
			(start 0.12065 -0.3048)
			(end 0.67945 -0.3048)
			(stroke
				(width 0.1)
				(type default)
			)
			(layer "F.Fab")
		)
		(fp_line
			(start 0.120396 0.3048)
			(end 0.120396 0.2794)
			(stroke
				(width 0.1)
				(type default)
			)
			(layer "F.Fab")
		)
		(fp_line
			(start 0.120396 0.2794)
			(end -0.12065 0.2794)
			(stroke
				(width 0.1)
				(type default)
			)
			(layer "F.Fab")
		)
		(fp_line
			(start -0.12065 0.3048)
			(end -0.67945 0.3048)
			(stroke
				(width 0.1)
				(type default)
			)
			(layer "F.Fab")
		)
		(fp_line
			(start -0.12065 0.2794)
			(end -0.12065 0.3048)
			(stroke
				(width 0.1)
				(type default)
			)
			(layer "F.Fab")
		)
		(fp_line
			(start -0.12065 -0.2794)
			(end 0.12065 -0.2794)
			(stroke
				(width 0.1)
				(type default)
			)
			(layer "F.Fab")
		)
		(fp_line
			(start -0.12065 -0.305054)
			(end -0.12065 -0.2794)
			(stroke
				(width 0.1)
				(type default)
			)
			(layer "F.Fab")
		)
		(fp_line
			(start -0.67945 0.3048)
			(end -0.67945 -0.305054)
			(stroke
				(width 0.1)
				(type default)
			)
			(layer "F.Fab")
		)
		(fp_line
			(start -0.67945 -0.305054)
			(end -0.12065 -0.305054)
			(stroke
				(width 0.1)
				(type default)
			)
			(layer "F.Fab")
		)
		(pad "1" smd circle
			(at -0.40005 0 180)
			(size 0 0)
			(layers "F.Cu" "F.Mask" "F.Paste")
			(net "RST_PERST_OCP_V3_2_BUF2_N")
		)
		(pad "2" smd circle
			(at 0.40005 0 180)
			(size 0 0)
			(layers "F.Cu" "F.Mask" "F.Paste")
			(net "RST_PERST1_OCP_V3_2_N")
		)
	)
)
